(kicad_pcb
	(version 20260206)
	(generator "pcbnew")
	(generator_version "10.0")
	(general
		(thickness 1.6)
		(legacy_teardrops no)
	)
	(paper "A4")
	(title_block
		(title "timecard-production-celestica-r4006 — R4006-B0001-02_R01.brd")
		(comment 1 "Time Appliance Project (Time Card) / footprints 1080-1084 of 1113")
	)
	(layers
		(0 "F.Cu" signal "TOP")
		(4 "In1.Cu" signal "L02_GND1")
		(6 "In2.Cu" signal "L03_SIG1")
		(8 "In3.Cu" signal "L04_GND2")
		(10 "In4.Cu" signal "L05_VCC1")
		(12 "In5.Cu" signal "L06_VCC2")
		(14 "In6.Cu" signal "L07_GND3")
		(16 "In7.Cu" signal "L08_SIG2")
		(18 "In8.Cu" signal "L09_GND4")
		(2 "B.Cu" signal "BOTTOM")
		(9 "F.Adhes" user "F.Adhesive")
		(11 "B.Adhes" user "B.Adhesive")
		(13 "F.Paste" user "Package Geometry/Pastemask Top")
		(15 "B.Paste" user "Package Geometry/Pastemask Bottom")
		(5 "F.SilkS" user "Ref Des/Silkscreen Top")
		(7 "B.SilkS" user "Ref Des/Silkscreen Bottom")
		(1 "F.Mask" user "Board Geometry/Soldermask Top")
		(3 "B.Mask" user "Board Geometry/Soldermask Bottom")
		(17 "Dwgs.User" user "User.Drawings")
		(19 "Cmts.User" user "User.Comments")
		(21 "Eco1.User" user "User.Eco1")
		(23 "Eco2.User" user "User.Eco2")
		(25 "Edge.Cuts" user "Board Geometry/Outline")
		(27 "Margin" user)
		(31 "F.CrtYd" user "Package Geometry/Place Bound Top")
		(29 "B.CrtYd" user "Package Geometry/Place Bound Bottom")
		(35 "F.Fab" user "Ref Des/Assembly Top")
		(33 "B.Fab" user "Ref Des/Assembly Bottom")
	)
	(footprint ""
		(layer "B.Cu")
		(at 46.736 -104.902 180)
		(property "Reference" "R33"
			(at 0.1778 1.61163 0)
			(unlocked yes)
			(layer "B.SilkS")
			(effects
				(font
					(size 0.7874 0.5842)
					(thickness 0.1524)
				)
				(justify mirror)
			)
		)
		(property "Value" "VAL*"
			(at -0.0508 3.159506 180)
			(unlocked yes)
			(layer "B.Fab")
			(hide yes)
			(effects
				(font
					(size 0.7874 0.5842)
					(thickness 0.1524)
				)
				(justify mirror)
			)
		)
		(property "Tolerance" "TOL*"
			(at -0.0508 4.124706 180)
			(unlocked yes)
			(layer "Cmts.User")
			(hide yes)
			(effects
				(font
					(size 0.7874 0.5842)
					(thickness 0.1524)
				)
				(justify mirror)
			)
		)
		(property "User Part Number" "PARTNUM*"
			(at -0.0508 5.089906 180)
			(unlocked yes)
			(layer "Cmts.User")
			(hide yes)
			(effects
				(font
					(size 0.7874 0.5842)
					(thickness 0.1524)
				)
				(justify mirror)
			)
		)
		(property "Device Type" "RESISTOR-G157-12R20-01,2.2OHM,A"
			(at 0 2.194306 180)
			(unlocked yes)
			(layer "B.Fab")
			(hide yes)
			(effects
				(font
					(size 0.7874 0.5842)
					(thickness 0.1524)
				)
				(justify mirror)
			)
		)
		(duplicate_pad_numbers_are_jumpers no)
		(fp_line
			(start 1.5748 0.9398)
			(end -1.5748 0.9398)
			(stroke
				(width 0.1)
				(type default)
			)
			(layer "B.SilkS")
		)
		(fp_line
			(start 1.5748 -0.9398)
			(end 1.5748 0.9398)
			(stroke
				(width 0.1)
				(type default)
			)
			(layer "B.SilkS")
		)
		(fp_line
			(start -1.5748 0.9398)
			(end -1.5748 -0.9398)
			(stroke
				(width 0.1)
				(type default)
			)
			(layer "B.SilkS")
		)
		(fp_line
			(start -1.5748 -0.9398)
			(end 1.5748 -0.9398)
			(stroke
				(width 0.1)
				(type default)
			)
			(layer "B.SilkS")
		)
		(fp_rect
			(start -1.5748 0.9398)
			(end 1.5748 -0.9398)
			(stroke
				(width 0)
				(type default)
			)
			(fill no)
			(layer "B.CrtYd")
		)
		(fp_line
			(start 1.016 0.635)
			(end -1.016 0.635)
			(stroke
				(width 0.1)
				(type default)
			)
			(layer "B.Fab")
		)
		(fp_line
			(start 1.016 -0.635)
			(end 1.016 0.635)
			(stroke
				(width 0.1)
				(type default)
			)
			(layer "B.Fab")
		)
		(fp_line
			(start -1.016 0.635)
			(end -1.016 -0.635)
			(stroke
				(width 0.1)
				(type default)
			)
			(layer "B.Fab")
		)
		(fp_line
			(start -1.016 -0.635)
			(end 1.016 -0.635)
			(stroke
				(width 0.1)
				(type default)
			)
			(layer "B.Fab")
		)
		(pad "1" smd rect
			(at 0.8382 0)
			(size 0.9652 1.3716)
			(layers "B.Cu" "B.Mask" "B.Paste")
			(net "UNNAMED_516_CAPACITOR_I37_2")
		)
		(pad "2" smd rect
			(at -0.8382 0)
			(size 0.9652 1.3716)
			(layers "B.Cu" "B.Mask" "B.Paste")
			(net "SG")
		)
		(zone
			(layer "B.Cu")
			(hatch none 0.5)
			(connect_pads
				(clearance 0)
			)
			(min_thickness 0.25)
			(keepout
				(tracks allowed)
				(vias not_allowed)
				(pads allowed)
				(copperpour not_allowed)
				(footprints allowed)
			)
			(placement
				(enabled no)
				(sheetname "")
			)
			(fill
				(thermal_gap 0.5)
				(thermal_bridge_width 0.5)
				(island_removal_mode 0)
			)
			(polygon
				(pts
					(xy 46.9646 -105.537) (xy 46.5074 -105.537) (xy 46.5074 -104.267) (xy 46.9646 -104.267)
				)
			)
		)
	)
	(footprint ""
		(layer "B.Cu")
		(at 106.847132 -38.323012 90)
		(property "Reference" "C169"
			(at -1.269492 -41.509442 270)
			(unlocked yes)
			(layer "B.SilkS")
			(effects
				(font
					(size 0.635 0.4064)
					(thickness 0.1524)
				)
				(justify mirror)
			)
		)
		(property "Value" "VAL*"
			(at 0 3.718306 90)
			(unlocked yes)
			(layer "B.Fab")
			(hide yes)
			(effects
				(font
					(size 0.7874 0.5842)
					(thickness 0.127)
				)
				(justify mirror)
			)
		)
		(property "Device Type" "CAPACITOR-G105-0B104-CK,0.1UF,A"
			(at 0 1.432306 90)
			(unlocked yes)
			(layer "B.Fab")
			(hide yes)
			(effects
				(font
					(size 0.7874 0.5842)
					(thickness 0.127)
				)
				(justify mirror)
			)
		)
		(property "User Part Number" "PARTNUM*"
			(at 0 2.575306 90)
			(unlocked yes)
			(layer "Cmts.User")
			(hide yes)
			(effects
				(font
					(size 0.7874 0.5842)
					(thickness 0.127)
				)
				(justify mirror)
			)
		)
		(property "Tolerance" "TOL*"
			(at 0 4.861306 90)
			(unlocked yes)
			(layer "Cmts.User")
			(hide yes)
			(effects
				(font
					(size 0.7874 0.5842)
					(thickness 0.127)
				)
				(justify mirror)
			)
		)
		(duplicate_pad_numbers_are_jumpers no)
		(fp_line
			(start 0.970026 -0.4699)
			(end -0.970026 -0.4699)
			(stroke
				(width 0.1)
				(type default)
			)
			(layer "B.SilkS")
		)
		(fp_line
			(start -0.970026 -0.4699)
			(end -0.970026 0.4699)
			(stroke
				(width 0.1)
				(type default)
			)
			(layer "B.SilkS")
		)
		(fp_line
			(start 0.970026 0.4699)
			(end 0.970026 -0.4699)
			(stroke
				(width 0.1)
				(type default)
			)
			(layer "B.SilkS")
		)
		(fp_line
			(start -0.970026 0.4699)
			(end 0.970026 0.4699)
			(stroke
				(width 0.1)
				(type default)
			)
			(layer "B.SilkS")
		)
		(fp_poly
			(pts
				(xy 0.970026 0.4699) (xy -0.970026 0.4699) (xy -0.970026 -0.4699) (xy 0.970026 -0.4699)
			)
			(stroke
				(width 0)
				(type default)
			)
			(fill no)
			(layer "B.CrtYd")
		)
		(fp_line
			(start 0.508 -0.3048)
			(end -0.508 -0.3048)
			(stroke
				(width 0.1)
				(type default)
			)
			(layer "B.Fab")
		)
		(fp_line
			(start -0.508 -0.3048)
			(end -0.508 0.3048)
			(stroke
				(width 0.1)
				(type default)
			)
			(layer "B.Fab")
		)
		(fp_line
			(start 0.508 0.3048)
			(end 0.508 -0.3048)
			(stroke
				(width 0.1)
				(type default)
			)
			(layer "B.Fab")
		)
		(fp_line
			(start -0.508 0.3048)
			(end 0.508 0.3048)
			(stroke
				(width 0.1)
				(type default)
			)
			(layer "B.Fab")
		)
		(pad "1" smd circle
			(at 0.500126 0 270)
			(size 0.635 0.635)
			(layers "B.Cu" "B.Mask" "B.Paste")
			(net "XP1R0V_FPGA_VCCINT")
		)
		(pad "2" smd circle
			(at -0.500126 0 270)
			(size 0.635 0.635)
			(layers "B.Cu" "B.Mask" "B.Paste")
			(net "SG")
		)
	)
	(footprint ""
		(layer "B.Cu")
		(at 152.781 -66.421)
		(property "Reference" "R81"
			(at 0 -1.10363 0)
			(unlocked yes)
			(layer "B.SilkS")
			(effects
				(font
					(size 0.7874 0.5842)
					(thickness 0.1524)
				)
				(justify mirror)
			)
		)
		(property "Value" "VAL*"
			(at -0.02032 2.13233 0)
			(unlocked yes)
			(layer "B.Fab")
			(hide yes)
			(effects
				(font
					(size 0.7874 0.5842)
					(thickness 0.1524)
				)
				(justify mirror)
			)
		)
		(property "Device Type" "RESISTOR-G155-133R0-01,33OHM,1%"
			(at -0.008382 1.210564 0)
			(unlocked yes)
			(layer "B.Fab")
			(hide yes)
			(effects
				(font
					(size 0.7874 0.5842)
					(thickness 0.1524)
				)
				(justify mirror)
			)
		)
		(property "User Part Number" "PARTNUM*"
			(at -0.02032 4.024884 0)
			(unlocked yes)
			(layer "Cmts.User")
			(hide yes)
			(effects
				(font
					(size 0.7874 0.5842)
					(thickness 0.1524)
				)
				(justify mirror)
			)
		)
		(property "Tolerance" "TOL*"
			(at -0.044704 3.05435 0)
			(unlocked yes)
			(layer "Cmts.User")
			(hide yes)
			(effects
				(font
					(size 0.7874 0.5842)
					(thickness 0.1524)
				)
				(justify mirror)
			)
		)
		(duplicate_pad_numbers_are_jumpers no)
		(fp_line
			(start -1.143 -0.5588)
			(end 1.143 -0.5588)
			(stroke
				(width 0.1)
				(type default)
			)
			(layer "B.SilkS")
		)
		(fp_line
			(start -1.143 0.5588)
			(end -1.143 -0.5588)
			(stroke
				(width 0.1)
				(type default)
			)
			(layer "B.SilkS")
		)
		(fp_line
			(start 1.143 -0.5588)
			(end 1.143 0.5588)
			(stroke
				(width 0.1)
				(type default)
			)
			(layer "B.SilkS")
		)
		(fp_line
			(start 1.143 0.5588)
			(end -1.143 0.5588)
			(stroke
				(width 0.1)
				(type default)
			)
			(layer "B.SilkS")
		)
		(fp_rect
			(start 1.143 0.5588)
			(end -1.143 -0.5588)
			(stroke
				(width 0)
				(type default)
			)
			(fill no)
			(layer "B.CrtYd")
		)
		(fp_line
			(start -0.508 -0.3048)
			(end 0.508 -0.3048)
			(stroke
				(width 0.1)
				(type default)
			)
			(layer "B.Fab")
		)
		(fp_line
			(start -0.508 0.3048)
			(end -0.508 -0.3048)
			(stroke
				(width 0.1)
				(type default)
			)
			(layer "B.Fab")
		)
		(fp_line
			(start 0.508 -0.3048)
			(end 0.508 0.3048)
			(stroke
				(width 0.1)
				(type default)
			)
			(layer "B.Fab")
		)
		(fp_line
			(start 0.508 0.3048)
			(end -0.508 0.3048)
			(stroke
				(width 0.1)
				(type default)
			)
			(layer "B.Fab")
		)
		(pad "1" smd rect
			(at 0.5334 0 180)
			(size 0.7112 0.6096)
			(layers "B.Cu" "B.Mask" "B.Paste")
			(net "R_MAC_UART_RX_FPGA_TX")
		)
		(pad "2" smd rect
			(at -0.5334 0 180)
			(size 0.7112 0.6096)
			(layers "B.Cu" "B.Mask" "B.Paste")
			(net "DBG_UART_MAC_RX")
		)
		(zone
			(layer "B.Cu")
			(hatch none 0.5)
			(connect_pads
				(clearance 0)
			)
			(min_thickness 0.25)
			(keepout
				(tracks allowed)
				(vias not_allowed)
				(pads allowed)
				(copperpour not_allowed)
				(footprints allowed)
			)
			(placement
				(enabled no)
				(sheetname "")
			)
			(fill
				(thermal_gap 0.5)
				(thermal_bridge_width 0.5)
				(island_removal_mode 0)
			)
			(polygon
				(pts
					(xy 152.8572 -66.1162) (xy 152.8572 -66.7258) (xy 152.7048 -66.7258) (xy 152.7048 -66.1162)
				)
			)
		)
	)
	(footprint ""
		(layer "B.Cu")
		(at 87.884 -34.163 90)
		(property "Reference" "C143"
			(at -3.429 -0.03937 270)
			(unlocked yes)
			(layer "B.SilkS")
			(effects
				(font
					(size 0.7874 0.5842)
					(thickness 0.1524)
				)
				(justify mirror)
			)
		)
		(property "Value" "VAL*"
			(at -0.0762 3.134106 90)
			(unlocked yes)
			(layer "B.Fab")
			(hide yes)
			(effects
				(font
					(size 0.7874 0.5842)
					(thickness 0.1524)
				)
				(justify mirror)
			)
		)
		(property "Tolerance" "TOL*"
			(at -0.0762 4.048506 90)
			(unlocked yes)
			(layer "Cmts.User")
			(hide yes)
			(effects
				(font
					(size 0.7874 0.5842)
					(thickness 0.1524)
				)
				(justify mirror)
			)
		)
		(property "User Part Number" "PARTNUM*"
			(at -0.1016 5.013706 90)
			(unlocked yes)
			(layer "Cmts.User")
			(hide yes)
			(effects
				(font
					(size 0.7874 0.5842)
					(thickness 0.1524)
				)
				(justify mirror)
			)
		)
		(property "Device Type" "CAPACITOR-G107-0F476-AM,47UF,2A"
			(at -0.0508 2.194306 90)
			(unlocked yes)
			(layer "B.Fab")
			(hide yes)
			(effects
				(font
					(size 0.7874 0.5842)
					(thickness 0.1524)
				)
				(justify mirror)
			)
		)
		(duplicate_pad_numbers_are_jumpers no)
		(fp_line
			(start 1.5748 -0.9398)
			(end 1.5748 0.9398)
			(stroke
				(width 0.1)
				(type default)
			)
			(layer "B.SilkS")
		)
		(fp_line
			(start -1.5748 -0.9398)
			(end 1.5748 -0.9398)
			(stroke
				(width 0.1)
				(type default)
			)
			(layer "B.SilkS")
		)
		(fp_line
			(start 1.5748 0.9398)
			(end -1.5748 0.9398)
			(stroke
				(width 0.1)
				(type default)
			)
			(layer "B.SilkS")
		)
		(fp_line
			(start -1.5748 0.9398)
			(end -1.5748 -0.9398)
			(stroke
				(width 0.1)
				(type default)
			)
			(layer "B.SilkS")
		)
		(fp_rect
			(start 1.5748 -0.9398)
			(end -1.5748 0.9398)
			(stroke
				(width 0)
				(type default)
			)
			(fill no)
			(layer "B.CrtYd")
		)
		(fp_line
			(start 1.016 -0.635)
			(end 1.016 0.635)
			(stroke
				(width 0.1)
				(type default)
			)
			(layer "B.Fab")
		)
		(fp_line
			(start -1.016 -0.635)
			(end 1.016 -0.635)
			(stroke
				(width 0.1)
				(type default)
			)
			(layer "B.Fab")
		)
		(fp_line
			(start 1.016 0.635)
			(end -1.016 0.635)
			(stroke
				(width 0.1)
				(type default)
			)
			(layer "B.Fab")
		)
		(fp_line
			(start -1.016 0.635)
			(end -1.016 -0.635)
			(stroke
				(width 0.1)
				(type default)
			)
			(layer "B.Fab")
		)
		(pad "1" smd rect
			(at 0.8382 0 270)
			(size 0.9652 1.3716)
			(layers "B.Cu" "B.Mask" "B.Paste")
			(net "XP1R2V_FPGA")
		)
		(pad "2" smd rect
			(at -0.8382 0 270)
			(size 0.9652 1.3716)
			(layers "B.Cu" "B.Mask" "B.Paste")
			(net "SG")
		)
		(zone
			(layer "B.Cu")
			(hatch none 0.5)
			(connect_pads
				(clearance 0)
			)
			(min_thickness 0.25)
			(keepout
				(tracks allowed)
				(vias not_allowed)
				(pads allowed)
				(copperpour not_allowed)
				(footprints allowed)
			)
			(placement
				(enabled no)
				(sheetname "")
			)
			(fill
				(thermal_gap 0.5)
				(thermal_bridge_width 0.5)
				(island_removal_mode 0)
			)
			(polygon
				(pts
					(xy 87.249 -34.3916) (xy 87.249 -33.9344) (xy 88.519 -33.9344) (xy 88.519 -34.3916)
				)
			)
		)
	)
	(footprint ""
		(layer "B.Cu")
		(at 115.062 -61.976 90)
		(property "Reference" "R215"
			(at 3.429 0.08763 270)
			(unlocked yes)
			(layer "B.SilkS")
			(effects
				(font
					(size 0.7874 0.5842)
					(thickness 0.1524)
				)
				(justify mirror)
			)
		)
		(property "Value" "VAL*"
			(at -0.02032 2.13233 90)
			(unlocked yes)
			(layer "B.Fab")
			(hide yes)
			(effects
				(font
					(size 0.7874 0.5842)
					(thickness 0.1524)
				)
				(justify mirror)
			)
		)
		(property "Device Type" "RESISTOR-G155-11002-01,10KOHM,A"
			(at -0.008382 1.210564 90)
			(unlocked yes)
			(layer "B.Fab")
			(hide yes)
			(effects
				(font
					(size 0.7874 0.5842)
					(thickness 0.1524)
				)
				(justify mirror)
			)
		)
		(property "User Part Number" "PARTNUM*"
			(at -0.02032 4.024884 90)
			(unlocked yes)
			(layer "Cmts.User")
			(hide yes)
			(effects
				(font
					(size 0.7874 0.5842)
					(thickness 0.1524)
				)
				(justify mirror)
			)
		)
		(property "Tolerance" "TOL*"
			(at -0.044704 3.05435 90)
			(unlocked yes)
			(layer "Cmts.User")
			(hide yes)
			(effects
				(font
					(size 0.7874 0.5842)
					(thickness 0.1524)
				)
				(justify mirror)
			)
		)
		(duplicate_pad_numbers_are_jumpers no)
		(fp_line
			(start 1.143 -0.5588)
			(end 1.143 0.5588)
			(stroke
				(width 0.1)
				(type default)
			)
			(layer "B.SilkS")
		)
		(fp_line
			(start -1.143 -0.5588)
			(end 1.143 -0.5588)
			(stroke
				(width 0.1)
				(type default)
			)
			(layer "B.SilkS")
		)
		(fp_line
			(start 1.143 0.5588)
			(end -1.143 0.5588)
			(stroke
				(width 0.1)
				(type default)
			)
			(layer "B.SilkS")
		)
		(fp_line
			(start -1.143 0.5588)
			(end -1.143 -0.5588)
			(stroke
				(width 0.1)
				(type default)
			)
			(layer "B.SilkS")
		)
		(fp_rect
			(start -1.143 0.5588)
			(end 1.143 -0.5588)
			(stroke
				(width 0)
				(type default)
			)
			(fill no)
			(layer "B.CrtYd")
		)
		(fp_line
			(start 0.508 -0.3048)
			(end 0.508 0.3048)
			(stroke
				(width 0.1)
				(type default)
			)
			(layer "B.Fab")
		)
		(fp_line
			(start -0.508 -0.3048)
			(end 0.508 -0.3048)
			(stroke
				(width 0.1)
				(type default)
			)
			(layer "B.Fab")
		)
		(fp_line
			(start 0.508 0.3048)
			(end -0.508 0.3048)
			(stroke
				(width 0.1)
				(type default)
			)
			(layer "B.Fab")
		)
		(fp_line
			(start -0.508 0.3048)
			(end -0.508 -0.3048)
			(stroke
				(width 0.1)
				(type default)
			)
			(layer "B.Fab")
		)
		(pad "1" smd rect
			(at 0.5334 0 270)
			(size 0.7112 0.6096)
			(layers "B.Cu" "B.Mask" "B.Paste")
			(net "XP3R3V_FPGA")
		)
		(pad "2" smd rect
			(at -0.5334 0 270)
			(size 0.7112 0.6096)
			(layers "B.Cu" "B.Mask" "B.Paste")
			(net "FPGA_BRD_REV1")
		)
		(zone
			(layer "B.Cu")
			(hatch none 0.5)
			(connect_pads
				(clearance 0)
			)
			(min_thickness 0.25)
			(keepout
				(tracks allowed)
				(vias not_allowed)
				(pads allowed)
				(copperpour not_allowed)
				(footprints allowed)
			)
			(placement
				(enabled no)
				(sheetname "")
			)
			(fill
				(thermal_gap 0.5)
				(thermal_bridge_width 0.5)
				(island_removal_mode 0)
			)
			(polygon
				(pts
					(xy 115.3668 -61.8998) (xy 115.3668 -62.0522) (xy 114.7572 -62.0522) (xy 114.7572 -61.8998)
				)
			)
		)
	)
)
